# S9S_MB_2U (Grand Teton) — schematic netlist excerpt (pin names and nets, part order shuffled) for the footprints in the layout excerpt that follows; sources: Cadence DE-HDL packaged netlist, KiCad conversion of 03242023_DA0F0TMBIJ0_F0T_Motherboard_J_brd_V01_OCP.brd

PC591  Q_CAP  2.2UF 16V 10% X6S  pkg C0603  page 259 : A = P3V3_AUX_VCC ; B = GND
R4804  Q_RES  1K 1% EMPTY  pkg 0402LF  page 306 : A = P3V3_AUX ; B = U205_VDD

(kicad_pcb
	(version 20260206)
	(generator "pcbnew")
	(generator_version "10.0")
	(general
		(thickness 1.6)
		(legacy_teardrops no)
	)
	(paper "A4")
	(title_block
		(title "03242023_DA0F0TMBIJ0_F0T_Motherboard_J_brd_V01_OCP.brd")
		(comment 1 "Grand Teton / footprints 3854-3855 of 6105")
	)
	(layers
		(0 "F.Cu" signal "TOP")
		(4 "In1.Cu" signal "GND")
		(6 "In2.Cu" signal "IN1")
		(8 "In3.Cu" signal "GND1")
		(10 "In4.Cu" signal "IN2")
		(12 "In5.Cu" signal "GND2")
		(14 "In6.Cu" signal "IN3")
		(16 "In7.Cu" signal "GND3")
		(18 "In8.Cu" signal "VCC")
		(20 "In9.Cu" signal "VCC1")
		(22 "In10.Cu" signal "GND4")
		(24 "In11.Cu" signal "IN4")
		(26 "In12.Cu" signal "GND5")
		(28 "In13.Cu" signal "IN5")
		(30 "In14.Cu" signal "GND6")
		(32 "In15.Cu" signal "IN6")
		(34 "In16.Cu" signal "GND7")
		(2 "B.Cu" signal "BOTTOM")
		(9 "F.Adhes" user "F.Adhesive")
		(11 "B.Adhes" user "B.Adhesive")
		(13 "F.Paste" user "Package Geometry/Pastemask Top")
		(15 "B.Paste" user "Package Geometry/Pastemask Bottom")
		(5 "F.SilkS" user "Ref Des/Silkscreen Top")
		(7 "B.SilkS" user "Ref Des/Silkscreen Bottom")
		(1 "F.Mask" user "Board Geometry/Soldermask Top")
		(3 "B.Mask" user "Board Geometry/Soldermask Bottom")
		(17 "Dwgs.User" user "User.Drawings")
		(19 "Cmts.User" user "User.Comments")
		(21 "Eco1.User" user "User.Eco1")
		(23 "Eco2.User" user "User.Eco2")
		(25 "Edge.Cuts" user "Board Geometry/Outline")
		(27 "Margin" user)
		(31 "F.CrtYd" user "Package Geometry/Place Bound Top")
		(29 "B.CrtYd" user "Package Geometry/Place Bound Bottom")
		(35 "F.Fab" user "Ref Des/Assembly Top")
		(33 "B.Fab" user "Ref Des/Assembly Bottom")
	)
	(footprint ""
		(layer "F.Cu")
		(at 210.560158 -104.96804)
		(property "Reference" "R4804"
			(at 0 0 0)
			(layer "F.SilkS")
			(hide yes)
			(effects
				(font
					(size 1.27 1.27)
				)
			)
		)
		(property "Value" ""
			(at 0 0 0)
			(layer "F.Fab")
			(effects
				(font
					(size 1.27 1.27)
				)
			)
		)
		(duplicate_pad_numbers_are_jumpers no)
		(fp_line
			(start -0.7874 -0.4064)
			(end 0.7874 -0.4064)
			(stroke
				(width 0.1524)
				(type default)
			)
			(layer "F.SilkS")
		)
		(fp_line
			(start -0.7874 0.4064)
			(end -0.7874 -0.4064)
			(stroke
				(width 0.1524)
				(type default)
			)
			(layer "F.SilkS")
		)
		(fp_line
			(start 0.7874 -0.4064)
			(end 0.7874 0.4064)
			(stroke
				(width 0.1524)
				(type default)
			)
			(layer "F.SilkS")
		)
		(fp_line
			(start 0.7874 0.4064)
			(end -0.7874 0.4064)
			(stroke
				(width 0.1524)
				(type default)
			)
			(layer "F.SilkS")
		)
		(fp_line
			(start -0.67945 -0.305054)
			(end -0.12065 -0.305054)
			(stroke
				(width 0.1)
				(type default)
			)
			(layer "F.Fab")
		)
		(fp_line
			(start -0.67945 0.3048)
			(end -0.67945 -0.305054)
			(stroke
				(width 0.1)
				(type default)
			)
			(layer "F.Fab")
		)
		(fp_line
			(start -0.12065 -0.305054)
			(end -0.12065 -0.2794)
			(stroke
				(width 0.1)
				(type default)
			)
			(layer "F.Fab")
		)
		(fp_line
			(start -0.12065 -0.2794)
			(end 0.12065 -0.2794)
			(stroke
				(width 0.1)
				(type default)
			)
			(layer "F.Fab")
		)
		(fp_line
			(start -0.12065 0.2794)
			(end -0.12065 0.3048)
			(stroke
				(width 0.1)
				(type default)
			)
			(layer "F.Fab")
		)
		(fp_line
			(start -0.12065 0.3048)
			(end -0.67945 0.3048)
			(stroke
				(width 0.1)
				(type default)
			)
			(layer "F.Fab")
		)
		(fp_line
			(start 0.120396 0.2794)
			(end -0.12065 0.2794)
			(stroke
				(width 0.1)
				(type default)
			)
			(layer "F.Fab")
		)
		(fp_line
			(start 0.120396 0.3048)
			(end 0.120396 0.2794)
			(stroke
				(width 0.1)
				(type default)
			)
			(layer "F.Fab")
		)
		(fp_line
			(start 0.12065 -0.3048)
			(end 0.67945 -0.3048)
			(stroke
				(width 0.1)
				(type default)
			)
			(layer "F.Fab")
		)
		(fp_line
			(start 0.12065 -0.2794)
			(end 0.12065 -0.3048)
			(stroke
				(width 0.1)
				(type default)
			)
			(layer "F.Fab")
		)
		(fp_line
			(start 0.67945 -0.3048)
			(end 0.67945 0.3048)
			(stroke
				(width 0.1)
				(type default)
			)
			(layer "F.Fab")
		)
		(fp_line
			(start 0.67945 0.3048)
			(end 0.120396 0.3048)
			(stroke
				(width 0.1)
				(type default)
			)
			(layer "F.Fab")
		)
		(pad "1" smd circle
			(at -0.40005 0)
			(size 0 0)
			(layers "F.Cu" "F.Mask" "F.Paste")
			(net "P3V3_AUX")
		)
		(pad "2" smd circle
			(at 0.40005 0)
			(size 0 0)
			(layers "F.Cu" "F.Mask" "F.Paste")
			(net "U205_VDD")
		)
	)
	(footprint ""
		(layer "F.Cu")
		(at 443.23 -74.640948 90)
		(property "Reference" "PC591"
			(at 0 0 90)
			(layer "F.SilkS")
			(hide yes)
			(effects
				(font
					(size 1.27 1.27)
				)
			)
		)
		(property "Value" ""
			(at 0 0 90)
			(layer "F.Fab")
			(effects
				(font
					(size 1.27 1.27)
				)
			)
		)
		(duplicate_pad_numbers_are_jumpers no)
		(fp_line
			(start 1.2954 -0.5842)
			(end 1.2954 0.5842)
			(stroke
				(width 0.1524)
				(type default)
			)
			(layer "F.SilkS")
		)
		(fp_line
			(start 0 -0.5842)
			(end 0 0.5842)
			(stroke
				(width 0.1524)
				(type default)
			)
			(layer "F.SilkS")
		)
		(fp_line
			(start -1.2954 -0.5842)
			(end 1.2954 -0.5842)
			(stroke
				(width 0.1524)
				(type default)
			)
			(layer "F.SilkS")
		)
		(fp_line
			(start 1.2954 0.5842)
			(end -1.2954 0.5842)
			(stroke
				(width 0.1524)
				(type default)
			)
			(layer "F.SilkS")
		)
		(fp_line
			(start -1.2954 0.5842)
			(end -1.2954 -0.5842)
			(stroke
				(width 0.1524)
				(type default)
			)
			(layer "F.SilkS")
		)
		(fp_line
			(start 0.8636 -0.4572)
			(end 0.8636 -0.4064)
			(stroke
				(width 0.1)
				(type default)
			)
			(layer "F.Fab")
		)
		(fp_line
			(start -0.8636 -0.4572)
			(end 0.8636 -0.4572)
			(stroke
				(width 0.1)
				(type default)
			)
			(layer "F.Fab")
		)
		(fp_line
			(start 1.1938 -0.4064)
			(end 1.1938 0.4064)
			(stroke
				(width 0.1)
				(type default)
			)
			(layer "F.Fab")
		)
		(fp_line
			(start 0.8636 -0.4064)
			(end 1.1938 -0.4064)
			(stroke
				(width 0.1)
				(type default)
			)
			(layer "F.Fab")
		)
		(fp_line
			(start -0.8636 -0.4064)
			(end -0.8636 -0.4572)
			(stroke
				(width 0.1)
				(type default)
			)
			(layer "F.Fab")
		)
		(fp_line
			(start -1.1938 -0.4064)
			(end -0.8636 -0.4064)
			(stroke
				(width 0.1)
				(type default)
			)
			(layer "F.Fab")
		)
		(fp_line
			(start 1.1938 0.4064)
			(end 0.8636 0.4064)
			(stroke
				(width 0.1)
				(type default)
			)
			(layer "F.Fab")
		)
		(fp_line
			(start 0.8636 0.4064)
			(end 0.8636 0.4572)
			(stroke
				(width 0.1)
				(type default)
			)
			(layer "F.Fab")
		)
		(fp_line
			(start -0.8636 0.4064)
			(end -1.1938 0.4064)
			(stroke
				(width 0.1)
				(type default)
			)
			(layer "F.Fab")
		)
		(fp_line
			(start -1.1938 0.4064)
			(end -1.1938 -0.4064)
			(stroke
				(width 0.1)
				(type default)
			)
			(layer "F.Fab")
		)
		(fp_line
			(start 0.8636 0.4572)
			(end -0.8636 0.4572)
			(stroke
				(width 0.1)
				(type default)
			)
			(layer "F.Fab")
		)
		(fp_line
			(start -0.8636 0.4572)
			(end -0.8636 0.4064)
			(stroke
				(width 0.1)
				(type default)
			)
			(layer "F.Fab")
		)
		(pad "1" smd rect
			(at -0.7366 0)
			(size 0.7112 0.8128)
			(layers "F.Cu" "F.Mask" "F.Paste")
			(net "P3V3_AUX_VCC")
		)
		(pad "2" smd rect
			(at 0.7366 0)
			(size 0.7112 0.8128)
			(layers "F.Cu" "F.Mask" "F.Paste")
			(net "GND")
		)
	)
)
